(kicad_pcb
	(version 20241229)
	(generator "pcbnew")
	(generator_version "9.0")
	(general
		(thickness 1.62)
		(legacy_teardrops no)
	)
	(paper "A4")
	(title_block
		(title "OCuLink to 10GbE adapter")
		(date "2026-02-23")
		(rev "1.1.0")
		(company "Antmicro Ltd")
		(comment 1 "www.antmicro.com")
		(comment 9 "footprints 249-253 of 510")
	)
	(layers
		(0 "F.Cu" signal)
		(4 "In1.Cu" signal)
		(6 "In2.Cu" signal)
		(8 "In3.Cu" signal)
		(10 "In4.Cu" signal)
		(12 "In5.Cu" signal)
		(14 "In6.Cu" signal)
		(2 "B.Cu" signal)
		(9 "F.Adhes" user "F.Adhesive")
		(11 "B.Adhes" user "B.Adhesive")
		(13 "F.Paste" user)
		(15 "B.Paste" user)
		(5 "F.SilkS" user "F.Silkscreen")
		(7 "B.SilkS" user "B.Silkscreen")
		(1 "F.Mask" user)
		(3 "B.Mask" user)
		(17 "Dwgs.User" user "User.Drawings")
		(19 "Cmts.User" user "User.Comments")
		(21 "Eco1.User" user "User.Eco1")
		(23 "Eco2.User" user "User.Eco2")
		(25 "Edge.Cuts" user)
		(27 "Margin" user)
		(31 "F.CrtYd" user "F.Courtyard")
		(29 "B.CrtYd" user "B.Courtyard")
		(35 "F.Fab" user)
		(33 "B.Fab" user)
	)
	(footprint "antmicro-footprints:R_0402_1005Metric"
		(layer "F.Cu")
		(at 88.1 112.45 90)
		(descr "Resistor SMD 0402")
		(tags "resistor SMD 0402")
		(property "Reference" "R75"
			(at -0.85 0.45 90)
			(layer "F.SilkS")
			(effects
				(font
					(size 0.7 0.7)
					(thickness 0.15)
				)
				(justify right bottom)
			)
		)
		(property "Value" "R_0R_0402"
			(at -1.011843 1.772046 90)
			(layer "F.Fab")
			(hide yes)
			(effects
				(font
					(size 0.7 0.7)
					(thickness 0.15)
				)
				(justify left bottom)
			)
		)
		(property "Datasheet" "https://industrial.panasonic.com/cdbs/www-data/pdf/RDA0000/AOA0000C301.pdf"
			(at 0 0 90)
			(layer "F.Fab")
			(hide yes)
			(effects
				(font
					(size 1.27 1.27)
					(thickness 0.15)
				)
			)
		)
		(property "Description" "SMD Chip Resistor, Jumper, 0 ohm, 100 mW, 0402 [1005 Metric], Thick Film, General Purpose"
			(at 0 0 90)
			(layer "F.Fab")
			(hide yes)
			(effects
				(font
					(size 1.27 1.27)
					(thickness 0.15)
				)
			)
		)
		(property "MPN" "ERJ2GE0R00X"
			(at 0 0 90)
			(unlocked yes)
			(layer "F.Fab")
			(hide yes)
			(effects
				(font
					(size 1 1)
					(thickness 0.15)
				)
			)
		)
		(property "Manufacturer" "Panasonic"
			(at 0 0 90)
			(unlocked yes)
			(layer "F.Fab")
			(hide yes)
			(effects
				(font
					(size 1 1)
					(thickness 0.15)
				)
			)
		)
		(property "License" "Apache-2.0"
			(at 0 0 90)
			(unlocked yes)
			(layer "F.Fab")
			(hide yes)
			(effects
				(font
					(size 1 1)
					(thickness 0.15)
				)
			)
		)
		(property "Author" "Antmicro"
			(at 0 0 90)
			(unlocked yes)
			(layer "F.Fab")
			(hide yes)
			(effects
				(font
					(size 1 1)
					(thickness 0.15)
				)
			)
		)
		(property "Val" "0R"
			(at 0 0 90)
			(unlocked yes)
			(layer "F.Fab")
			(hide yes)
			(effects
				(font
					(size 1 1)
					(thickness 0.15)
				)
			)
		)
		(property "Tolerance" "~"
			(at 0 0 90)
			(unlocked yes)
			(layer "F.Fab")
			(hide yes)
			(effects
				(font
					(size 1 1)
					(thickness 0.15)
				)
			)
		)
		(property "Current" "1A"
			(at 0 0 90)
			(unlocked yes)
			(layer "F.Fab")
			(hide yes)
			(effects
				(font
					(size 1 1)
					(thickness 0.15)
				)
			)
		)
		(sheetname "/X710-AT2 10GbE/")
		(sheetfile "x710-at2-10gbe.kicad_sch")
		(attr smd)
		(fp_rect
			(start -0.925 -0.47)
			(end 0.925 0.47)
			(stroke
				(width 0.05)
				(type default)
			)
			(fill no)
			(layer "F.CrtYd")
		)
		(fp_rect
			(start -0.5 -0.25)
			(end 0.5 0.25)
			(stroke
				(width 0.15)
				(type solid)
			)
			(fill no)
			(layer "F.Fab")
		)
		(pad "1" smd roundrect
			(at -0.48 0 90)
			(size 0.59 0.64)
			(layers "F.Cu" "F.Mask" "F.Paste")
			(roundrect_rratio 0.25)
			(net 28 "GND")
			(pintype "passive")
		)
		(pad "2" smd roundrect
			(at 0.48 0 90)
			(size 0.59 0.64)
			(layers "F.Cu" "F.Mask" "F.Paste")
			(roundrect_rratio 0.25)
			(net 294 "/X710-AT2 10GbE/TPIN_5")
			(pintype "passive")
		)
	)
	(footprint "antmicro-footprints:MP_Pad6mm_Drill3.2mm"
		(layer "F.Cu")
		(at 62.975 77.995)
		(property "Reference" "MP5"
			(at 0 -3.2 0)
			(layer "F.SilkS")
			(hide yes)
			(effects
				(font
					(size 0.7 0.7)
					(thickness 0.15)
				)
				(justify left bottom)
			)
		)
		(property "Value" "MP_Pad6mm_Drill3.2mm"
			(at 0 3.9 0)
			(layer "F.Fab")
			(hide yes)
			(effects
				(font
					(size 0.7 0.7)
					(thickness 0.15)
				)
				(justify left bottom)
			)
		)
		(property "Description" "Mechanical part"
			(at 0 0 0)
			(layer "F.Fab")
			(hide yes)
			(effects
				(font
					(size 1.27 1.27)
					(thickness 0.15)
				)
			)
		)
		(property "Author" "Antmicro"
			(at 0 0 0)
			(unlocked yes)
			(layer "F.Fab")
			(hide yes)
			(effects
				(font
					(size 1 1)
					(thickness 0.15)
				)
			)
		)
		(property "License" "Apache-2.0"
			(at 0 0 0)
			(unlocked yes)
			(layer "F.Fab")
			(hide yes)
			(effects
				(font
					(size 1 1)
					(thickness 0.15)
				)
			)
		)
		(sheetname "/")
		(sheetfile "oculink-to-10gbe-adapter.kicad_sch")
		(attr exclude_from_pos_files exclude_from_bom)
		(fp_circle
			(center 0 0)
			(end 3.25 0)
			(stroke
				(width 0.05)
				(type default)
			)
			(fill no)
			(layer "F.CrtYd")
		)
		(fp_text user "License: Apache-2.0"
			(at -0.178 8.425 0)
			(layer "F.Fab")
			(effects
				(font
					(size 0.7 0.7)
					(thickness 0.15)
				)
				(justify left bottom)
			)
		)
		(fp_text user "Author: Antmicro"
			(at -0.178 7.225 0)
			(layer "F.Fab")
			(effects
				(font
					(size 0.7 0.7)
					(thickness 0.15)
				)
				(justify left bottom)
			)
		)
		(fp_text user "${REFERENCE}"
			(at -0.178 6.025 0)
			(layer "F.Fab")
			(effects
				(font
					(size 0.7 0.7)
					(thickness 0.15)
				)
				(justify left bottom)
			)
		)
		(pad "1" thru_hole circle
			(at 0 0)
			(size 6 6)
			(drill 3.2)
			(layers "*.Cu" "*.Mask")
			(remove_unused_layers no)
			(net 28 "GND")
			(pintype "passive")
		)
	)
	(footprint "antmicro-footprints:C_0402_1005Metric"
		(layer "F.Cu")
		(at 97.399999 109.1)
		(descr "Capacitor SMD 0402")
		(tags "capacitor SMD 0402")
		(property "Reference" "C69"
			(at -2.249999 15.7 0)
			(layer "F.SilkS")
			(effects
				(font
					(size 0.7 0.7)
					(thickness 0.15)
				)
				(justify left bottom)
			)
		)
		(property "Value" "C_100n_0402"
			(at -1.022927 2.155213 0)
			(layer "F.Fab")
			(hide yes)
			(effects
				(font
					(size 0.7 0.7)
					(thickness 0.15)
				)
				(justify left bottom)
			)
		)
		(property "Datasheet" "https://www.murata.com/products/productdetail?partno=GRM155R61H104KE14%23"
			(at 0 0 0)
			(layer "F.Fab")
			(hide yes)
			(effects
				(font
					(size 1.27 1.27)
					(thickness 0.15)
				)
			)
		)
		(property "Description" "SMD Multilayer Ceramic Capacitor, 0.1 µF, 50 V, 0402 [1005 Metric], ± 10%, X5R, GRM Series"
			(at 0 0 0)
			(layer "F.Fab")
			(hide yes)
			(effects
				(font
					(size 1.27 1.27)
					(thickness 0.15)
				)
			)
		)
		(property "MPN" "GRM155R61H104KE14D"
			(at 0 0 0)
			(unlocked yes)
			(layer "F.Fab")
			(hide yes)
			(effects
				(font
					(size 1 1)
					(thickness 0.15)
				)
			)
		)
		(property "Val" "100n"
			(at 0 0 0)
			(unlocked yes)
			(layer "F.Fab")
			(hide yes)
			(effects
				(font
					(size 1 1)
					(thickness 0.15)
				)
			)
		)
		(property "Voltage" "50V"
			(at 0 0 0)
			(unlocked yes)
			(layer "F.Fab")
			(hide yes)
			(effects
				(font
					(size 1 1)
					(thickness 0.15)
				)
			)
		)
		(property "Dielectric" "X5R"
			(at 0 0 0)
			(unlocked yes)
			(layer "F.Fab")
			(hide yes)
			(effects
				(font
					(size 1 1)
					(thickness 0.15)
				)
			)
		)
		(property "Manufacturer" "Murata"
			(at 0 0 0)
			(unlocked yes)
			(layer "F.Fab")
			(hide yes)
			(effects
				(font
					(size 1 1)
					(thickness 0.15)
				)
			)
		)
		(property "License" "Apache-2.0"
			(at 0 0 0)
			(unlocked yes)
			(layer "F.Fab")
			(hide yes)
			(effects
				(font
					(size 1 1)
					(thickness 0.15)
				)
			)
		)
		(property "Author" "Antmicro"
			(at 0 0 0)
			(unlocked yes)
			(layer "F.Fab")
			(hide yes)
			(effects
				(font
					(size 1 1)
					(thickness 0.15)
				)
			)
		)
		(sheetname "/X710-AT2 10GbE/")
		(sheetfile "x710-at2-10gbe.kicad_sch")
		(attr smd)
		(fp_rect
			(start -0.925 -0.47)
			(end 0.925 0.47)
			(stroke
				(width 0.05)
				(type default)
			)
			(fill no)
			(layer "F.CrtYd")
		)
		(fp_line
			(start -0.494 -0.25)
			(end 0.504 -0.25)
			(stroke
				(width 0.15)
				(type solid)
			)
			(layer "F.Fab")
		)
		(fp_line
			(start -0.494 0.248)
			(end -0.494 -0.25)
			(stroke
				(width 0.15)
				(type solid)
			)
			(layer "F.Fab")
		)
		(fp_line
			(start 0.504 -0.25)
			(end 0.504 0.248)
			(stroke
				(width 0.15)
				(type solid)
			)
			(layer "F.Fab")
		)
		(fp_line
			(start 0.504 0.248)
			(end -0.494 0.248)
			(stroke
				(width 0.15)
				(type solid)
			)
			(layer "F.Fab")
		)
		(pad "1" smd roundrect
			(at -0.48 0)
			(size 0.59 0.64)
			(layers "F.Cu" "F.Mask" "F.Paste")
			(roundrect_rratio 0.25)
			(net 31 "/X710-AT2 10GbE/25MHZ_OSC.-")
			(pintype "passive")
		)
		(pad "2" smd roundrect
			(at 0.48 0)
			(size 0.59 0.64)
			(layers "F.Cu" "F.Mask" "F.Paste")
			(roundrect_rratio 0.25)
			(net 73 "/X710-AT2 10GbE/25MHZ_OSC_AC.-")
			(pintype "passive")
		)
	)
	(footprint "antmicro-footprints:R_0402_1005Metric"
		(layer "F.Cu")
		(at 54.099999 85.149999 -90)
		(descr "Resistor SMD 0402")
		(tags "resistor SMD 0402")
		(property "Reference" "R12"
			(at -1.029999 2.989999 90)
			(layer "F.SilkS")
			(effects
				(font
					(size 0.7 0.7)
					(thickness 0.15)
				)
				(justify right top)
			)
		)
		(property "Value" "R_30k_0402"
			(at -1.011843 1.772046 90)
			(layer "F.Fab")
			(hide yes)
			(effects
				(font
					(size 0.7 0.7)
					(thickness 0.15)
				)
				(justify right top)
			)
		)
		(property "Datasheet" "https://www.bourns.com/docs/product-datasheets/cr.pdf"
			(at 0 0 90)
			(layer "F.Fab")
			(hide yes)
			(effects
				(font
					(size 1.27 1.27)
					(thickness 0.15)
				)
			)
		)
		(property "Description" "SMD Chip Resistor, 30 kohm, ± 1%, 63 mW, 0402 [1005 Metric], Thick Film, General Purpose"
			(at 0 0 90)
			(layer "F.Fab")
			(hide yes)
			(effects
				(font
					(size 1.27 1.27)
					(thickness 0.15)
				)
			)
		)
		(property "MPN" "CR0402-FX-3002GLF"
			(at 0 0 270)
			(unlocked yes)
			(layer "F.Fab")
			(hide yes)
			(effects
				(font
					(size 1 1)
					(thickness 0.15)
				)
			)
		)
		(property "Manufacturer" "Bourns"
			(at 0 0 270)
			(unlocked yes)
			(layer "F.Fab")
			(hide yes)
			(effects
				(font
					(size 1 1)
					(thickness 0.15)
				)
			)
		)
		(property "License" "Apache-2.0"
			(at 0 0 270)
			(unlocked yes)
			(layer "F.Fab")
			(hide yes)
			(effects
				(font
					(size 1 1)
					(thickness 0.15)
				)
			)
		)
		(property "Author" "Antmicro"
			(at 0 0 270)
			(unlocked yes)
			(layer "F.Fab")
			(hide yes)
			(effects
				(font
					(size 1 1)
					(thickness 0.15)
				)
			)
		)
		(property "Val" "30k"
			(at 0 0 270)
			(unlocked yes)
			(layer "F.Fab")
			(hide yes)
			(effects
				(font
					(size 1 1)
					(thickness 0.15)
				)
			)
		)
		(property "Tolerance" "1%"
			(at 0 0 270)
			(unlocked yes)
			(layer "F.Fab")
			(hide yes)
			(effects
				(font
					(size 1 1)
					(thickness 0.15)
				)
			)
		)
		(sheetname "/Power/")
		(sheetfile "power.kicad_sch")
		(attr smd)
		(fp_rect
			(start -0.925 -0.47)
			(end 0.925 0.47)
			(stroke
				(width 0.05)
				(type default)
			)
			(fill no)
			(layer "F.CrtYd")
		)
		(fp_rect
			(start -0.5 -0.25)
			(end 0.5 0.25)
			(stroke
				(width 0.15)
				(type solid)
			)
			(fill no)
			(layer "F.Fab")
		)
		(pad "1" smd roundrect
			(at -0.48 0 270)
			(size 0.59 0.64)
			(layers "F.Cu" "F.Mask" "F.Paste")
			(roundrect_rratio 0.25)
			(net 28 "GND")
			(pintype "passive")
		)
		(pad "2" smd roundrect
			(at 0.48 0 270)
			(size 0.59 0.64)
			(layers "F.Cu" "F.Mask" "F.Paste")
			(roundrect_rratio 0.25)
			(net 329 "/Power/VCCD_FB")
			(pintype "passive")
		)
	)
	(footprint "antmicro-footprints:RJ45_JTH-0024NL"
		(layer "F.Cu")
		(at 79.05 132.39 180)
		(property "Reference" "J3"
			(at -2.555 4.4 0)
			(unlocked yes)
			(layer "F.SilkS")
			(effects
				(font
					(size 0.7 0.7)
					(thickness 0.15)
				)
				(justify left bottom)
			)
		)
		(property "Value" "Bus_RJ45_JTH-0024NL"
			(at 5.06 1 180)
			(unlocked yes)
			(layer "F.Fab")
			(hide yes)
			(effects
				(font
					(size 0.7 0.7)
					(thickness 0.15)
				)
				(justify left bottom)
			)
		)
		(property "Datasheet" "https://www.mouser.com/datasheet/2/447/JTH_0024NL-3072047.pdf"
			(at 0 0 0)
			(layer "F.Fab")
			(hide yes)
			(effects
				(font
					(size 1.27 1.27)
					(thickness 0.15)
				)
			)
		)
		(property "Description" "Modular Connectors / Ethernet Connectors 1X1 TAB DOWN W/LED'S ETHERNET (NON PoE)"
			(at 0 0 0)
			(layer "F.Fab")
			(hide yes)
			(effects
				(font
					(size 1.27 1.27)
					(thickness 0.15)
				)
			)
		)
		(property "MPN" "JTH-0024NL"
			(at 0 0 180)
			(unlocked yes)
			(layer "F.Fab")
			(hide yes)
			(effects
				(font
					(size 1 1)
					(thickness 0.15)
				)
			)
		)
		(property "Manufacturer" "Pulse Electronics"
			(at 0 0 180)
			(unlocked yes)
			(layer "F.Fab")
			(hide yes)
			(effects
				(font
					(size 1 1)
					(thickness 0.15)
				)
			)
		)
		(property "Author" "Antmicro"
			(at 0 0 180)
			(unlocked yes)
			(layer "F.Fab")
			(hide yes)
			(effects
				(font
					(size 1 1)
					(thickness 0.15)
				)
			)
		)
		(property "License" "Apache-2.0"
			(at 0 0 180)
			(unlocked yes)
			(layer "F.Fab")
			(hide yes)
			(effects
				(font
					(size 1 1)
					(thickness 0.15)
				)
			)
		)
		(property ki_fp_filters "CONN18_5-2337992-8_TEC")
		(sheetname "/2xRJ45/")
		(sheetfile "2xrj45.kicad_sch")
		(attr through_hole)
		(fp_line
			(start 14 4)
			(end 14 -5.25)
			(stroke
				(width 0.1)
				(type default)
			)
			(layer "F.SilkS")
		)
		(fp_line
			(start -3.75 4)
			(end 14 4)
			(stroke
				(width 0.1)
				(type default)
			)
			(layer "F.SilkS")
		)
		(fp_line
			(start -3.75 -5.25)
			(end -3.75 4)
			(stroke
				(width 0.1)
				(type default)
			)
			(layer "F.SilkS")
		)
		(fp_rect
			(start -5.4 -20.72)
			(end 15.58 4.45)
			(stroke
				(width 0.05)
				(type solid)
			)
			(fill no)
			(layer "F.CrtYd")
		)
		(fp_text user "${REFERENCE}"
			(at -5.75 6.45 180)
			(unlocked yes)
			(layer "F.Fab")
			(effects
				(font
					(size 0.7 0.7)
					(thickness 0.15)
				)
				(justify left bottom)
			)
		)
		(fp_text user "License: Apache-2.0"
			(at -5.75 7.65 180)
			(layer "F.Fab")
			(effects
				(font
					(size 0.7 0.7)
					(thickness 0.15)
				)
				(justify left bottom)
			)
		)
		(fp_text user "Author: Antmicro"
			(at -5.75 8.85 180)
			(layer "F.Fab")
			(effects
				(font
					(size 0.7 0.7)
					(thickness 0.15)
				)
				(justify left bottom)
			)
		)
		(pad "" np_thru_hole circle
			(at 0.245 -6.6 180)
			(size 3.2 3.2)
			(drill 3.2)
			(layers "*.Cu" "*.Mask")
		)
		(pad "" np_thru_hole circle
			(at 9.895 -6.6 180)
			(size 3.2 3.2)
			(drill 3.2)
			(layers "*.Cu" "*.Mask")
		)
		(pad "1" thru_hole circle
			(at 0 0 180)
			(size 1.39 1.39)
			(drill 0.89)
			(layers "*.Cu" "*.Mask")
			(remove_unused_layers no)
			(net 299 "/2xRJ45/P0_CT")
			(pinfunction "CT3")
			(pintype "bidirectional")
		)
		(pad "2" thru_hole circle
			(at 2.03 0 180)
			(size 1.39 1.39)
			(drill 0.89)
			(layers "*.Cu" "*.Mask")
			(remove_unused_layers no)
			(net 50 "/2xRJ45/Ethernet_P0.D3-")
			(pinfunction "T2-")
			(pintype "bidirectional")
		)
		(pad "3" thru_hole circle
			(at 4.06 0 180)
			(size 1.39 1.39)
			(drill 0.89)
			(layers "*.Cu" "*.Mask")
			(remove_unused_layers no)
			(net 58 "/2xRJ45/Ethernet_P0.D3+")
			(pinfunction "T2+")
			(pintype "bidirectional")
		)
		(pad "4" thru_hole circle
			(at 6.09 0 180)
			(size 1.39 1.39)
			(drill 0.89)
			(layers "*.Cu" "*.Mask")
			(remove_unused_layers no)
			(net 51 "/2xRJ45/Ethernet_P0.D2+")
			(pinfunction "T3+")
			(pintype "bidirectional")
		)
		(pad "5" thru_hole circle
			(at 8.12 0 180)
			(size 1.39 1.39)
			(drill 0.89)
			(layers "*.Cu" "*.Mask")
			(remove_unused_layers no)
			(net 48 "/2xRJ45/Ethernet_P0.D2-")
			(pinfunction "T3-")
			(pintype "bidirectional")
		)
		(pad "6" thru_hole circle
			(at 10.15 0 180)
			(size 1.39 1.39)
			(drill 0.89)
			(layers "*.Cu" "*.Mask")
			(remove_unused_layers no)
			(net 299 "/2xRJ45/P0_CT")
			(pinfunction "CT2")
			(pintype "bidirectional")
		)
		(pad "7" thru_hole circle
			(at -1.02 2.54 180)
			(size 1.39 1.39)
			(drill 0.89)
			(layers "*.Cu" "*.Mask")
			(remove_unused_layers no)
			(net 299 "/2xRJ45/P0_CT")
			(pinfunction "CT4")
			(pintype "bidirectional")
		)
		(pad "8" thru_hole circle
			(at 1.01 2.54 180)
			(size 1.39 1.39)
			(drill 0.89)
			(layers "*.Cu" "*.Mask")
			(remove_unused_layers no)
			(net 55 "/2xRJ45/Ethernet_P0.D4+")
			(pinfunction "T1+")
			(pintype "bidirectional")
		)
		(pad "9" thru_hole circle
			(at 3.04 2.54 180)
			(size 1.39 1.39)
			(drill 0.89)
			(layers "*.Cu" "*.Mask")
			(remove_unused_layers no)
			(net 57 "/2xRJ45/Ethernet_P0.D4-")
			(pinfunction "T1-")
			(pintype "bidirectional")
		)
		(pad "10" thru_hole circle
			(at 7.11 2.54 180)
			(size 1.39 1.39)
			(drill 0.89)
			(layers "*.Cu" "*.Mask")
			(remove_unused_layers no)
			(net 49 "/2xRJ45/Ethernet_P0.D1-")
			(pinfunction "T4-")
			(pintype "bidirectional")
		)
		(pad "11" thru_hole circle
			(at 9.14 2.54 180)
			(size 1.39 1.39)
			(drill 0.89)
			(layers "*.Cu" "*.Mask")
			(remove_unused_layers no)
			(net 56 "/2xRJ45/Ethernet_P0.D1+")
			(pinfunction "T4+")
			(pintype "bidirectional")
		)
		(pad "12" thru_hole circle
			(at 11.17 2.54 180)
			(size 1.39 1.39)
			(drill 0.89)
			(layers "*.Cu" "*.Mask")
			(remove_unused_layers no)
			(net 299 "/2xRJ45/P0_CT")
			(pinfunction "CT1")
			(pintype "bidirectional")
		)
		(pad "13" thru_hole circle
			(at 12.59 -12.95 180)
			(size 1.77 1.77)
			(drill 1.27)
			(layers "*.Cu" "*.Mask")
			(remove_unused_layers no)
			(net 54 "Net-(J3-LED_GRN-)")
			(pinfunction "LED_GRN-")
			(pintype "passive")
		)
		(pad "14" thru_hole circle
			(at 12.59 -15.49 180)
			(size 1.77 1.77)
			(drill 1.27)
			(layers "*.Cu" "*.Mask")
			(remove_unused_layers no)
			(net 7 "+3V3")
			(pinfunction "LED_GRN+")
			(pintype "passive")
		)
		(pad "15" thru_hole circle
			(at -2.45 -10.41 180)
			(size 1.77 1.77)
			(drill 1.27)
			(layers "*.Cu" "*.Mask")
			(remove_unused_layers no)
			(net 52 "Net-(J3-LED_YG_Y-)")
			(pinfunction "LED_YG_Y-")
			(pintype "passive")
		)
		(pad "16" thru_hole circle
			(at -2.45 -12.95 180)
			(size 1.77 1.77)
			(drill 1.27)
			(layers "*.Cu" "*.Mask")
			(remove_unused_layers no)
			(net 7 "+3V3")
			(pinfunction "LED_COM+")
			(pintype "passive")
		)
		(pad "17" thru_hole circle
			(at -2.45 -15.49 180)
			(size 1.77 1.77)
			(drill 1.27)
			(layers "*.Cu" "*.Mask")
			(remove_unused_layers no)
			(net 53 "Net-(J3-LED_YG_G-)")
			(pinfunction "LED_YG_G-")
			(pintype "passive")
		)
		(pad "SH" thru_hole circle
			(at -3.72 -6.6 180)
			(size 2.07 2.07)
			(drill 1.57)
			(layers "*.Cu" "*.Mask")
			(remove_unused_layers no)
			(net 28 "GND")
			(pinfunction "SHIELD")
			(pintype "passive")
		)
		(pad "SH" thru_hole circle
			(at 13.86 -6.6 180)
			(size 2.07 2.07)
			(drill 1.57)
			(layers "*.Cu" "*.Mask")
			(remove_unused_layers no)
			(net 28 "GND")
			(pinfunction "SHIELD")
			(pintype "passive")
		)
	)
)
